(kicad_pcb
	(version 20260206)
	(generator "pcbnew")
	(generator_version "10.0")
	(general
		(thickness 1.6)
		(legacy_teardrops no)
	)
	(paper "A4")
	(title_block
		(title "04192023_DAF0TMB3IC0_F0TG_MB_C_brd_V02_OCP.brd")
		(comment 1 "Grand Teton / footprints 2644-2648 of 8354")
	)
	(layers
		(0 "F.Cu" signal "TOP")
		(4 "In1.Cu" signal "GND")
		(6 "In2.Cu" signal "IN1")
		(8 "In3.Cu" signal "GND1")
		(10 "In4.Cu" signal "IN2")
		(12 "In5.Cu" signal "GND2")
		(14 "In6.Cu" signal "IN3")
		(16 "In7.Cu" signal "GND3")
		(18 "In8.Cu" signal "VCC")
		(20 "In9.Cu" signal "VCC1")
		(22 "In10.Cu" signal "GND4")
		(24 "In11.Cu" signal "IN4")
		(26 "In12.Cu" signal "GND5")
		(28 "In13.Cu" signal "IN5")
		(30 "In14.Cu" signal "GND6")
		(32 "In15.Cu" signal "IN6")
		(34 "In16.Cu" signal "GND7")
		(2 "B.Cu" signal "BOTTOM")
		(9 "F.Adhes" user "F.Adhesive")
		(11 "B.Adhes" user "B.Adhesive")
		(13 "F.Paste" user "Package Geometry/Pastemask Top")
		(15 "B.Paste" user "Package Geometry/Pastemask Bottom")
		(5 "F.SilkS" user "Ref Des/Silkscreen Top")
		(7 "B.SilkS" user "Ref Des/Silkscreen Bottom")
		(1 "F.Mask" user "Board Geometry/Soldermask Top")
		(3 "B.Mask" user "Board Geometry/Soldermask Bottom")
		(17 "Dwgs.User" user "User.Drawings")
		(19 "Cmts.User" user "User.Comments")
		(21 "Eco1.User" user "User.Eco1")
		(23 "Eco2.User" user "User.Eco2")
		(25 "Edge.Cuts" user "Board Geometry/Outline")
		(27 "Margin" user)
		(31 "F.CrtYd" user "Package Geometry/Place Bound Top")
		(29 "B.CrtYd" user "Package Geometry/Place Bound Bottom")
		(35 "F.Fab" user "Ref Des/Assembly Top")
		(33 "B.Fab" user "Ref Des/Assembly Bottom")
	)
	(footprint ""
		(layer "F.Cu")
		(at 83.439254 -337.643724 90)
		(property "Reference" "PC369"
			(at 0 0 90)
			(layer "F.SilkS")
			(hide yes)
			(effects
				(font
					(size 1.27 1.27)
				)
			)
		)
		(property "Value" ""
			(at 0 0 90)
			(layer "F.Fab")
			(effects
				(font
					(size 1.27 1.27)
				)
			)
		)
		(duplicate_pad_numbers_are_jumpers no)
		(fp_line
			(start 0.7874 -0.4064)
			(end 0.7874 0.4064)
			(stroke
				(width 0.1524)
				(type default)
			)
			(layer "F.SilkS")
		)
		(fp_line
			(start -0.7874 -0.4064)
			(end 0.7874 -0.4064)
			(stroke
				(width 0.1524)
				(type default)
			)
			(layer "F.SilkS")
		)
		(fp_line
			(start 0.7874 0.4064)
			(end 0.481076 0.4064)
			(stroke
				(width 0.1524)
				(type default)
			)
			(layer "F.SilkS")
		)
		(fp_line
			(start -0.306324 0.4064)
			(end -0.7874 0.4064)
			(stroke
				(width 0.1524)
				(type default)
			)
			(layer "F.SilkS")
		)
		(fp_line
			(start -0.7874 0.4064)
			(end -0.7874 -0.4064)
			(stroke
				(width 0.1524)
				(type default)
			)
			(layer "F.SilkS")
		)
		(fp_line
			(start -0.12065 -0.305054)
			(end -0.12065 -0.2794)
			(stroke
				(width 0.1)
				(type default)
			)
			(layer "F.Fab")
		)
		(fp_line
			(start -0.67945 -0.305054)
			(end -0.12065 -0.305054)
			(stroke
				(width 0.1)
				(type default)
			)
			(layer "F.Fab")
		)
		(fp_line
			(start 0.67945 -0.3048)
			(end 0.67945 0.3048)
			(stroke
				(width 0.1)
				(type default)
			)
			(layer "F.Fab")
		)
		(fp_line
			(start 0.12065 -0.3048)
			(end 0.67945 -0.3048)
			(stroke
				(width 0.1)
				(type default)
			)
			(layer "F.Fab")
		)
		(fp_line
			(start 0.12065 -0.2794)
			(end 0.12065 -0.3048)
			(stroke
				(width 0.1)
				(type default)
			)
			(layer "F.Fab")
		)
		(fp_line
			(start -0.12065 -0.2794)
			(end 0.12065 -0.2794)
			(stroke
				(width 0.1)
				(type default)
			)
			(layer "F.Fab")
		)
		(fp_line
			(start 0.120396 0.2794)
			(end -0.12065 0.2794)
			(stroke
				(width 0.1)
				(type default)
			)
			(layer "F.Fab")
		)
		(fp_line
			(start -0.12065 0.2794)
			(end -0.12065 0.3048)
			(stroke
				(width 0.1)
				(type default)
			)
			(layer "F.Fab")
		)
		(fp_line
			(start 0.67945 0.3048)
			(end 0.120396 0.3048)
			(stroke
				(width 0.1)
				(type default)
			)
			(layer "F.Fab")
		)
		(fp_line
			(start 0.120396 0.3048)
			(end 0.120396 0.2794)
			(stroke
				(width 0.1)
				(type default)
			)
			(layer "F.Fab")
		)
		(fp_line
			(start -0.12065 0.3048)
			(end -0.67945 0.3048)
			(stroke
				(width 0.1)
				(type default)
			)
			(layer "F.Fab")
		)
		(fp_line
			(start -0.67945 0.3048)
			(end -0.67945 -0.305054)
			(stroke
				(width 0.1)
				(type default)
			)
			(layer "F.Fab")
		)
		(pad "1" smd circle
			(at -0.40005 0 90)
			(size 0 0)
			(layers "F.Cu" "F.Mask" "F.Paste")
			(net "PVDDCR_CPU1_P1_VCC1")
		)
		(pad "2" smd circle
			(at 0.40005 0 90)
			(size 0 0)
			(layers "F.Cu" "F.Mask" "F.Paste")
			(net "GND")
		)
	)
	(footprint ""
		(layer "F.Cu")
		(at 97.279968 -425.817284 -90)
		(property "Reference" "R4058"
			(at 0 0 270)
			(layer "F.SilkS")
			(hide yes)
			(effects
				(font
					(size 1.27 1.27)
				)
			)
		)
		(property "Value" ""
			(at 0 0 270)
			(layer "F.Fab")
			(effects
				(font
					(size 1.27 1.27)
				)
			)
		)
		(duplicate_pad_numbers_are_jumpers no)
		(fp_line
			(start -0.7874 0.4064)
			(end -0.7874 -0.4064)
			(stroke
				(width 0.1524)
				(type default)
			)
			(layer "F.SilkS")
		)
		(fp_line
			(start 0.7874 0.4064)
			(end -0.7874 0.4064)
			(stroke
				(width 0.1524)
				(type default)
			)
			(layer "F.SilkS")
		)
		(fp_line
			(start -0.7874 -0.4064)
			(end 0.7874 -0.4064)
			(stroke
				(width 0.1524)
				(type default)
			)
			(layer "F.SilkS")
		)
		(fp_line
			(start 0.7874 -0.4064)
			(end 0.7874 0.4064)
			(stroke
				(width 0.1524)
				(type default)
			)
			(layer "F.SilkS")
		)
		(fp_line
			(start -0.67945 0.3048)
			(end -0.67945 -0.305054)
			(stroke
				(width 0.1)
				(type default)
			)
			(layer "F.Fab")
		)
		(fp_line
			(start -0.12065 0.3048)
			(end -0.67945 0.3048)
			(stroke
				(width 0.1)
				(type default)
			)
			(layer "F.Fab")
		)
		(fp_line
			(start 0.120396 0.3048)
			(end 0.120396 0.2794)
			(stroke
				(width 0.1)
				(type default)
			)
			(layer "F.Fab")
		)
		(fp_line
			(start 0.67945 0.3048)
			(end 0.120396 0.3048)
			(stroke
				(width 0.1)
				(type default)
			)
			(layer "F.Fab")
		)
		(fp_line
			(start -0.12065 0.2794)
			(end -0.12065 0.3048)
			(stroke
				(width 0.1)
				(type default)
			)
			(layer "F.Fab")
		)
		(fp_line
			(start 0.120396 0.2794)
			(end -0.12065 0.2794)
			(stroke
				(width 0.1)
				(type default)
			)
			(layer "F.Fab")
		)
		(fp_line
			(start -0.12065 -0.2794)
			(end 0.12065 -0.2794)
			(stroke
				(width 0.1)
				(type default)
			)
			(layer "F.Fab")
		)
		(fp_line
			(start 0.12065 -0.2794)
			(end 0.12065 -0.3048)
			(stroke
				(width 0.1)
				(type default)
			)
			(layer "F.Fab")
		)
		(fp_line
			(start 0.12065 -0.3048)
			(end 0.67945 -0.3048)
			(stroke
				(width 0.1)
				(type default)
			)
			(layer "F.Fab")
		)
		(fp_line
			(start 0.67945 -0.3048)
			(end 0.67945 0.3048)
			(stroke
				(width 0.1)
				(type default)
			)
			(layer "F.Fab")
		)
		(fp_line
			(start -0.67945 -0.305054)
			(end -0.12065 -0.305054)
			(stroke
				(width 0.1)
				(type default)
			)
			(layer "F.Fab")
		)
		(fp_line
			(start -0.12065 -0.305054)
			(end -0.12065 -0.2794)
			(stroke
				(width 0.1)
				(type default)
			)
			(layer "F.Fab")
		)
		(pad "1" smd circle
			(at -0.40005 0 270)
			(size 0 0)
			(layers "F.Cu" "F.Mask" "F.Paste")
			(net "P3V3_AUX")
		)
		(pad "2" smd circle
			(at 0.40005 0 270)
			(size 0 0)
			(layers "F.Cu" "F.Mask" "F.Paste")
			(net "PRSNT_SWB_N")
		)
	)
	(footprint ""
		(layer "F.Cu")
		(at 350.44761 -63.904876 180)
		(property "Reference" "R485"
			(at 0 0 180)
			(layer "F.SilkS")
			(hide yes)
			(effects
				(font
					(size 1.27 1.27)
				)
			)
		)
		(property "Value" ""
			(at 0 0 180)
			(layer "F.Fab")
			(effects
				(font
					(size 1.27 1.27)
				)
			)
		)
		(duplicate_pad_numbers_are_jumpers no)
		(fp_line
			(start 0.7874 0.4064)
			(end -0.7874 0.4064)
			(stroke
				(width 0.1524)
				(type default)
			)
			(layer "F.SilkS")
		)
		(fp_line
			(start 0.7874 -0.4064)
			(end 0.7874 0.4064)
			(stroke
				(width 0.1524)
				(type default)
			)
			(layer "F.SilkS")
		)
		(fp_line
			(start -0.7874 0.4064)
			(end -0.7874 -0.4064)
			(stroke
				(width 0.1524)
				(type default)
			)
			(layer "F.SilkS")
		)
		(fp_line
			(start -0.7874 -0.4064)
			(end 0.7874 -0.4064)
			(stroke
				(width 0.1524)
				(type default)
			)
			(layer "F.SilkS")
		)
		(fp_line
			(start 0.67945 0.3048)
			(end 0.120396 0.3048)
			(stroke
				(width 0.1)
				(type default)
			)
			(layer "F.Fab")
		)
		(fp_line
			(start 0.67945 -0.3048)
			(end 0.67945 0.3048)
			(stroke
				(width 0.1)
				(type default)
			)
			(layer "F.Fab")
		)
		(fp_line
			(start 0.12065 -0.2794)
			(end 0.12065 -0.3048)
			(stroke
				(width 0.1)
				(type default)
			)
			(layer "F.Fab")
		)
		(fp_line
			(start 0.12065 -0.3048)
			(end 0.67945 -0.3048)
			(stroke
				(width 0.1)
				(type default)
			)
			(layer "F.Fab")
		)
		(fp_line
			(start 0.120396 0.3048)
			(end 0.120396 0.2794)
			(stroke
				(width 0.1)
				(type default)
			)
			(layer "F.Fab")
		)
		(fp_line
			(start 0.120396 0.2794)
			(end -0.12065 0.2794)
			(stroke
				(width 0.1)
				(type default)
			)
			(layer "F.Fab")
		)
		(fp_line
			(start -0.12065 0.3048)
			(end -0.67945 0.3048)
			(stroke
				(width 0.1)
				(type default)
			)
			(layer "F.Fab")
		)
		(fp_line
			(start -0.12065 0.2794)
			(end -0.12065 0.3048)
			(stroke
				(width 0.1)
				(type default)
			)
			(layer "F.Fab")
		)
		(fp_line
			(start -0.12065 -0.2794)
			(end 0.12065 -0.2794)
			(stroke
				(width 0.1)
				(type default)
			)
			(layer "F.Fab")
		)
		(fp_line
			(start -0.12065 -0.305054)
			(end -0.12065 -0.2794)
			(stroke
				(width 0.1)
				(type default)
			)
			(layer "F.Fab")
		)
		(fp_line
			(start -0.67945 0.3048)
			(end -0.67945 -0.305054)
			(stroke
				(width 0.1)
				(type default)
			)
			(layer "F.Fab")
		)
		(fp_line
			(start -0.67945 -0.305054)
			(end -0.12065 -0.305054)
			(stroke
				(width 0.1)
				(type default)
			)
			(layer "F.Fab")
		)
		(pad "1" smd circle
			(at -0.40005 0 180)
			(size 0 0)
			(layers "F.Cu" "F.Mask" "F.Paste")
			(net "CPU0_XTRIG_L7")
		)
		(pad "2" smd circle
			(at 0.40005 0 180)
			(size 0 0)
			(layers "F.Cu" "F.Mask" "F.Paste")
			(net "CPU0_XTRIG_R1_L7")
		)
	)
	(footprint ""
		(layer "F.Cu")
		(at 105.84561 -67.60591)
		(property "Reference" "R6222"
			(at 0 0 0)
			(layer "F.SilkS")
			(hide yes)
			(effects
				(font
					(size 1.27 1.27)
				)
			)
		)
		(property "Value" ""
			(at 0 0 0)
			(layer "F.Fab")
			(effects
				(font
					(size 1.27 1.27)
				)
			)
		)
		(duplicate_pad_numbers_are_jumpers no)
		(fp_line
			(start -0.7874 -0.4064)
			(end 0.7874 -0.4064)
			(stroke
				(width 0.1524)
				(type default)
			)
			(layer "F.SilkS")
		)
		(fp_line
			(start -0.7874 0.4064)
			(end -0.7874 -0.4064)
			(stroke
				(width 0.1524)
				(type default)
			)
			(layer "F.SilkS")
		)
		(fp_line
			(start 0.7874 -0.4064)
			(end 0.7874 0.4064)
			(stroke
				(width 0.1524)
				(type default)
			)
			(layer "F.SilkS")
		)
		(fp_line
			(start 0.7874 0.4064)
			(end -0.7874 0.4064)
			(stroke
				(width 0.1524)
				(type default)
			)
			(layer "F.SilkS")
		)
		(fp_line
			(start -0.67945 -0.305054)
			(end -0.12065 -0.305054)
			(stroke
				(width 0.1)
				(type default)
			)
			(layer "F.Fab")
		)
		(fp_line
			(start -0.67945 0.3048)
			(end -0.67945 -0.305054)
			(stroke
				(width 0.1)
				(type default)
			)
			(layer "F.Fab")
		)
		(fp_line
			(start -0.12065 -0.305054)
			(end -0.12065 -0.2794)
			(stroke
				(width 0.1)
				(type default)
			)
			(layer "F.Fab")
		)
		(fp_line
			(start -0.12065 -0.2794)
			(end 0.12065 -0.2794)
			(stroke
				(width 0.1)
				(type default)
			)
			(layer "F.Fab")
		)
		(fp_line
			(start -0.12065 0.2794)
			(end -0.12065 0.3048)
			(stroke
				(width 0.1)
				(type default)
			)
			(layer "F.Fab")
		)
		(fp_line
			(start -0.12065 0.3048)
			(end -0.67945 0.3048)
			(stroke
				(width 0.1)
				(type default)
			)
			(layer "F.Fab")
		)
		(fp_line
			(start 0.120396 0.2794)
			(end -0.12065 0.2794)
			(stroke
				(width 0.1)
				(type default)
			)
			(layer "F.Fab")
		)
		(fp_line
			(start 0.120396 0.3048)
			(end 0.120396 0.2794)
			(stroke
				(width 0.1)
				(type default)
			)
			(layer "F.Fab")
		)
		(fp_line
			(start 0.12065 -0.3048)
			(end 0.67945 -0.3048)
			(stroke
				(width 0.1)
				(type default)
			)
			(layer "F.Fab")
		)
		(fp_line
			(start 0.12065 -0.2794)
			(end 0.12065 -0.3048)
			(stroke
				(width 0.1)
				(type default)
			)
			(layer "F.Fab")
		)
		(fp_line
			(start 0.67945 -0.3048)
			(end 0.67945 0.3048)
			(stroke
				(width 0.1)
				(type default)
			)
			(layer "F.Fab")
		)
		(fp_line
			(start 0.67945 0.3048)
			(end 0.120396 0.3048)
			(stroke
				(width 0.1)
				(type default)
			)
			(layer "F.Fab")
		)
		(pad "1" smd circle
			(at -0.40005 0)
			(size 0 0)
			(layers "F.Cu" "F.Mask" "F.Paste")
			(net "P3V3_AUX")
		)
		(pad "2" smd circle
			(at 0.40005 0)
			(size 0 0)
			(layers "F.Cu" "F.Mask" "F.Paste")
			(net "USB_CPU0_ADD_A0")
		)
	)
	(footprint ""
		(layer "F.Cu")
		(at 177.984912 -412.257748 180)
		(property "Reference" "R347"
			(at 0 0 180)
			(layer "F.SilkS")
			(hide yes)
			(effects
				(font
					(size 1.27 1.27)
				)
			)
		)
		(property "Value" ""
			(at 0 0 180)
			(layer "F.Fab")
			(effects
				(font
					(size 1.27 1.27)
				)
			)
		)
		(duplicate_pad_numbers_are_jumpers no)
		(fp_line
			(start 0.7874 0.4064)
			(end -0.7874 0.4064)
			(stroke
				(width 0.1524)
				(type default)
			)
			(layer "F.SilkS")
		)
		(fp_line
			(start 0.7874 -0.4064)
			(end 0.7874 0.4064)
			(stroke
				(width 0.1524)
				(type default)
			)
			(layer "F.SilkS")
		)
		(fp_line
			(start -0.7874 0.4064)
			(end -0.7874 -0.4064)
			(stroke
				(width 0.1524)
				(type default)
			)
			(layer "F.SilkS")
		)
		(fp_line
			(start -0.7874 -0.4064)
			(end 0.7874 -0.4064)
			(stroke
				(width 0.1524)
				(type default)
			)
			(layer "F.SilkS")
		)
		(fp_line
			(start 0.67945 0.3048)
			(end 0.120396 0.3048)
			(stroke
				(width 0.1)
				(type default)
			)
			(layer "F.Fab")
		)
		(fp_line
			(start 0.67945 -0.3048)
			(end 0.67945 0.3048)
			(stroke
				(width 0.1)
				(type default)
			)
			(layer "F.Fab")
		)
		(fp_line
			(start 0.12065 -0.2794)
			(end 0.12065 -0.3048)
			(stroke
				(width 0.1)
				(type default)
			)
			(layer "F.Fab")
		)
		(fp_line
			(start 0.12065 -0.3048)
			(end 0.67945 -0.3048)
			(stroke
				(width 0.1)
				(type default)
			)
			(layer "F.Fab")
		)
		(fp_line
			(start 0.120396 0.3048)
			(end 0.120396 0.2794)
			(stroke
				(width 0.1)
				(type default)
			)
			(layer "F.Fab")
		)
		(fp_line
			(start 0.120396 0.2794)
			(end -0.12065 0.2794)
			(stroke
				(width 0.1)
				(type default)
			)
			(layer "F.Fab")
		)
		(fp_line
			(start -0.12065 0.3048)
			(end -0.67945 0.3048)
			(stroke
				(width 0.1)
				(type default)
			)
			(layer "F.Fab")
		)
		(fp_line
			(start -0.12065 0.2794)
			(end -0.12065 0.3048)
			(stroke
				(width 0.1)
				(type default)
			)
			(layer "F.Fab")
		)
		(fp_line
			(start -0.12065 -0.2794)
			(end 0.12065 -0.2794)
			(stroke
				(width 0.1)
				(type default)
			)
			(layer "F.Fab")
		)
		(fp_line
			(start -0.12065 -0.305054)
			(end -0.12065 -0.2794)
			(stroke
				(width 0.1)
				(type default)
			)
			(layer "F.Fab")
		)
		(fp_line
			(start -0.67945 0.3048)
			(end -0.67945 -0.305054)
			(stroke
				(width 0.1)
				(type default)
			)
			(layer "F.Fab")
		)
		(fp_line
			(start -0.67945 -0.305054)
			(end -0.12065 -0.305054)
			(stroke
				(width 0.1)
				(type default)
			)
			(layer "F.Fab")
		)
		(pad "1" smd circle
			(at -0.40005 0 180)
			(size 0 0)
			(layers "F.Cu" "F.Mask" "F.Paste")
			(net "SMB_SML1_PMBUS_HSC_SCL")
		)
		(pad "2" smd circle
			(at 0.40005 0 180)
			(size 0 0)
			(layers "F.Cu" "F.Mask" "F.Paste")
			(net "SMB_SML1_PMBUS_HSC_R1_SCL")
		)
	)
)
